(kicad_pcb
	(version 20260206)
	(generator "pcbnew")
	(generator_version "10.0")
	(general
		(thickness 1.6)
		(legacy_teardrops no)
	)
	(paper "A4")
	(title_block
		(title "Bryce Canyon_SCC_16316-1_OCP.brd")
		(comment 1 "Bryce Canyon / footprints 185-190 of 1561")
	)
	(layers
		(0 "F.Cu" signal "TOP")
		(4 "In1.Cu" signal "L2GND")
		(6 "In2.Cu" signal "L3")
		(8 "In3.Cu" signal "L4VCC")
		(10 "In4.Cu" signal "L5VCC")
		(12 "In5.Cu" signal "L6")
		(14 "In6.Cu" signal "L7GND")
		(2 "B.Cu" signal "BOTTOM")
		(9 "F.Adhes" user "F.Adhesive")
		(11 "B.Adhes" user "B.Adhesive")
		(13 "F.Paste" user "Package Geometry/Pastemask Top")
		(15 "B.Paste" user "Package Geometry/Pastemask Bottom")
		(5 "F.SilkS" user "Ref Des/Silkscreen Top")
		(7 "B.SilkS" user "Ref Des/Silkscreen Bottom")
		(1 "F.Mask" user "Board Geometry/Soldermask Top")
		(3 "B.Mask" user "Board Geometry/Soldermask Bottom")
		(17 "Dwgs.User" user "User.Drawings")
		(19 "Cmts.User" user "User.Comments")
		(21 "Eco1.User" user "User.Eco1")
		(23 "Eco2.User" user "User.Eco2")
		(25 "Edge.Cuts" user "Board Geometry/Outline")
		(27 "Margin" user)
		(31 "F.CrtYd" user "Package Geometry/Place Bound Top")
		(29 "B.CrtYd" user "Package Geometry/Place Bound Bottom")
		(35 "F.Fab" user "Ref Des/Assembly Top")
		(33 "B.Fab" user "Ref Des/Assembly Bottom")
	)
	(footprint ""
		(layer "F.Cu")
		(at 91.44 -86.487 -90)
		(property "Reference" "R305"
			(at 0 0 270)
			(layer "F.SilkS")
			(hide yes)
			(effects
				(font
					(size 1.27 1.27)
				)
			)
		)
		(property "Value" "10KR2F-2-GP"
			(at 0.064008 -3.993896 270)
			(unlocked yes)
			(layer "F.Fab")
			(hide yes)
			(effects
				(font
					(size 1.016 1.016)
					(thickness 0.1524)
				)
			)
		)
		(property "Device Type" "R402H16"
			(at 0.064008 -5.517896 270)
			(unlocked yes)
			(layer "F.Fab")
			(hide yes)
			(effects
				(font
					(size 1.016 1.016)
					(thickness 0.1524)
				)
			)
		)
		(duplicate_pad_numbers_are_jumpers no)
		(fp_line
			(start -0.508 -0.9398)
			(end -0.508 0.9398)
			(stroke
				(width 0.1524)
				(type default)
			)
			(layer "F.SilkS")
		)
		(fp_line
			(start 0.508 -0.9398)
			(end -0.508 -0.9398)
			(stroke
				(width 0.1524)
				(type default)
			)
			(layer "F.SilkS")
		)
		(fp_rect
			(start -0.508 0.9398)
			(end 0.508 -0.9398)
			(stroke
				(width 0)
				(type default)
			)
			(fill no)
			(layer "F.CrtYd")
		)
		(fp_rect
			(start -0.508 0.9398)
			(end 0.508 -0.9398)
			(stroke
				(width 0)
				(type default)
			)
			(fill no)
			(layer "F.Fab")
		)
		(pad "1" smd custom
			(at 0 -0.4445 270)
			(size 0.1397 0.1397)
			(layers "F.Cu" "F.Mask" "F.Paste")
			(net "BMC_LOC_HEARTBEAT_LS")
			(options
				(clearance outline)
				(anchor circle)
			)
			(primitives
				(gr_poly
					(pts
						(arc
							(start -0.1778 -0.2794)
							(mid -0.249642 -0.249642)
							(end -0.2794 -0.1778)
						)
						(arc
							(start -0.2794 0.1778)
							(mid -0.249642 0.249642)
							(end -0.1778 0.2794)
						)
						(arc
							(start 0.1778 0.2794)
							(mid 0.249642 0.249642)
							(end 0.2794 0.1778)
						)
						(arc
							(start 0.2794 -0.1778)
							(mid 0.249642 -0.249642)
							(end 0.1778 -0.2794)
						)
					)
					(width 0)
					(fill yes)
				)
			)
		)
		(pad "2" smd custom
			(at 0 0.4445 270)
			(size 0.1397 0.1397)
			(layers "F.Cu" "F.Mask" "F.Paste")
			(net "GND")
			(options
				(clearance outline)
				(anchor circle)
			)
			(primitives
				(gr_poly
					(pts
						(arc
							(start -0.1778 -0.2794)
							(mid -0.249642 -0.249642)
							(end -0.2794 -0.1778)
						)
						(arc
							(start -0.2794 0.1778)
							(mid -0.249642 0.249642)
							(end -0.1778 0.2794)
						)
						(arc
							(start 0.1778 0.2794)
							(mid 0.249642 0.249642)
							(end 0.2794 0.1778)
						)
						(arc
							(start 0.2794 -0.1778)
							(mid 0.249642 -0.249642)
							(end 0.1778 -0.2794)
						)
					)
					(width 0)
					(fill yes)
				)
			)
		)
	)
	(footprint ""
		(layer "F.Cu")
		(at 179.02047 -82.652108)
		(property "Reference" "C627"
			(at 0 0 0)
			(layer "F.SilkS")
			(hide yes)
			(effects
				(font
					(size 1.27 1.27)
				)
			)
		)
		(property "Value" "SC10U6D3V5KX-4GP"
			(at -0.0762 -6.1214 0)
			(unlocked yes)
			(layer "F.Fab")
			(hide yes)
			(effects
				(font
					(size 1.016 1.016)
					(thickness 0.1524)
				)
			)
		)
		(property "Device Type" "C805H58"
			(at -0.0762 -8.1534 0)
			(unlocked yes)
			(layer "F.Fab")
			(hide yes)
			(effects
				(font
					(size 1.016 1.016)
					(thickness 0.1524)
				)
			)
		)
		(duplicate_pad_numbers_are_jumpers no)
		(fp_line
			(start 0.635 0)
			(end -0.635 0)
			(stroke
				(width 0.508)
				(type default)
			)
			(layer "F.SilkS")
		)
		(fp_rect
			(start -0.9652 1.778)
			(end 0.9652 -1.778)
			(stroke
				(width 0)
				(type default)
			)
			(fill no)
			(layer "F.CrtYd")
		)
		(fp_poly
			(pts
				(xy -0.9652 -1.778) (xy 0.9652 -1.778) (xy 0.9652 1.778) (xy -0.9652 1.778)
			)
			(stroke
				(width 0)
				(type default)
			)
			(fill no)
			(layer "F.Fab")
		)
		(pad "1" smd rect
			(at 0 -0.9652)
			(size 1.397 1.143)
			(layers "F.Cu" "F.Mask" "F.Paste")
			(net "P0V975")
		)
		(pad "2" smd rect
			(at 0 0.9652)
			(size 1.397 1.143)
			(layers "F.Cu" "F.Mask" "F.Paste")
			(net "GND")
		)
	)
	(footprint ""
		(layer "F.Cu")
		(at 132.220208 -46.386242 90)
		(property "Reference" "VIA12"
			(at 0 0 90)
			(layer "F.SilkS")
			(hide yes)
			(effects
				(font
					(size 1.27 1.27)
				)
			)
		)
		(property "Value" "100OHM-8L-1D6MM-L13-GP"
			(at 3.2893 0.0508 90)
			(unlocked yes)
			(layer "F.Fab")
			(hide yes)
			(effects
				(font
					(size 1.016 1.016)
					(thickness 0.1524)
				)
			)
		)
		(property "Device Type" "VIA-PCIE-4P-409091"
			(at 3.2893 -1.4732 90)
			(unlocked yes)
			(layer "F.Fab")
			(hide yes)
			(effects
				(font
					(size 1.016 1.016)
					(thickness 0.1524)
				)
			)
		)
		(duplicate_pad_numbers_are_jumpers no)
		(fp_rect
			(start -2.0447 0.4572)
			(end 2.0447 -0.4572)
			(stroke
				(width 0)
				(type default)
			)
			(fill no)
			(layer "F.CrtYd")
		)
		(fp_rect
			(start -2.0447 0.4572)
			(end 2.0447 -0.4572)
			(stroke
				(width 0)
				(type default)
			)
			(fill no)
			(layer "F.Fab")
		)
		(pad "1" thru_hole circle
			(at -1.5875 0 90)
			(size 0.508 0.508)
			(drill 0.254)
			(layers "*.Cu" "*.Mask")
			(remove_unused_layers no)
			(net "GND")
			(clearance 0.2032)
			(thermal_gap 0.2032)
		)
		(pad "2" thru_hole circle
			(at -0.5715 0 90)
			(size 0.508 0.508)
			(drill 0.254)
			(layers "*.Cu" "*.Mask")
			(remove_unused_layers no)
			(net "PHY_IOC_TO_SCC_C_43_DP")
			(clearance 0.2032)
			(thermal_gap 0.2032)
		)
		(pad "3" thru_hole circle
			(at 0.5715 0 90)
			(size 0.508 0.508)
			(drill 0.254)
			(layers "*.Cu" "*.Mask")
			(remove_unused_layers no)
			(net "PHY_IOC_TO_SCC_C_43_DN")
			(clearance 0.2032)
			(thermal_gap 0.2032)
		)
		(pad "4" thru_hole circle
			(at 1.5875 0 90)
			(size 0.508 0.508)
			(drill 0.254)
			(layers "*.Cu" "*.Mask")
			(remove_unused_layers no)
			(net "GND")
			(clearance 0.2032)
			(thermal_gap 0.2032)
		)
	)
	(footprint ""
		(layer "F.Cu")
		(at 190.87338 -78.49108 180)
		(property "Reference" "R365"
			(at 0 0 180)
			(layer "F.SilkS")
			(hide yes)
			(effects
				(font
					(size 1.27 1.27)
				)
			)
		)
		(property "Value" "4K7R2F-GP"
			(at 0.064008 -3.993896 180)
			(unlocked yes)
			(layer "F.Fab")
			(hide yes)
			(effects
				(font
					(size 1.016 1.016)
					(thickness 0.1524)
				)
			)
		)
		(property "Device Type" "R402H16"
			(at 0.064008 -5.517896 180)
			(unlocked yes)
			(layer "F.Fab")
			(hide yes)
			(effects
				(font
					(size 1.016 1.016)
					(thickness 0.1524)
				)
			)
		)
		(duplicate_pad_numbers_are_jumpers no)
		(fp_line
			(start 0.508 -0.9398)
			(end -0.508 -0.9398)
			(stroke
				(width 0.1524)
				(type default)
			)
			(layer "F.SilkS")
		)
		(fp_line
			(start -0.508 -0.9398)
			(end -0.508 0.9398)
			(stroke
				(width 0.1524)
				(type default)
			)
			(layer "F.SilkS")
		)
		(fp_rect
			(start -0.508 0.9398)
			(end 0.508 -0.9398)
			(stroke
				(width 0)
				(type default)
			)
			(fill no)
			(layer "F.CrtYd")
		)
		(fp_rect
			(start -0.508 0.9398)
			(end 0.508 -0.9398)
			(stroke
				(width 0)
				(type default)
			)
			(fill no)
			(layer "F.Fab")
		)
		(pad "1" smd custom
			(at 0 -0.4445 180)
			(size 0.1397 0.1397)
			(layers "F.Cu" "F.Mask" "F.Paste")
			(net "TEMP2_A1")
			(options
				(clearance outline)
				(anchor circle)
			)
			(primitives
				(gr_poly
					(pts
						(arc
							(start -0.1778 -0.2794)
							(mid -0.249642 -0.249642)
							(end -0.2794 -0.1778)
						)
						(arc
							(start -0.2794 0.1778)
							(mid -0.249642 0.249642)
							(end -0.1778 0.2794)
						)
						(arc
							(start 0.1778 0.2794)
							(mid 0.249642 0.249642)
							(end 0.2794 0.1778)
						)
						(arc
							(start 0.2794 -0.1778)
							(mid 0.249642 -0.249642)
							(end 0.1778 -0.2794)
						)
					)
					(width 0)
					(fill yes)
				)
			)
		)
		(pad "2" smd custom
			(at 0 0.4445 180)
			(size 0.1397 0.1397)
			(layers "F.Cu" "F.Mask" "F.Paste")
			(net "GND")
			(options
				(clearance outline)
				(anchor circle)
			)
			(primitives
				(gr_poly
					(pts
						(arc
							(start -0.1778 -0.2794)
							(mid -0.249642 -0.249642)
							(end -0.2794 -0.1778)
						)
						(arc
							(start -0.2794 0.1778)
							(mid -0.249642 0.249642)
							(end -0.1778 0.2794)
						)
						(arc
							(start 0.1778 0.2794)
							(mid 0.249642 0.249642)
							(end 0.2794 0.1778)
						)
						(arc
							(start 0.2794 -0.1778)
							(mid 0.249642 -0.249642)
							(end 0.1778 -0.2794)
						)
					)
					(width 0)
					(fill yes)
				)
			)
		)
	)
	(footprint ""
		(layer "F.Cu")
		(at 63.97498 -100.50018)
		(property "Reference" "U10"
			(at 0 0 0)
			(layer "F.SilkS")
			(hide yes)
			(effects
				(font
					(size 1.27 1.27)
				)
			)
		)
		(property "Value" "TPS53318DQPR-GP"
			(at -5.022088 -6.851904 0)
			(unlocked yes)
			(layer "F.Fab")
			(hide yes)
			(effects
				(font
					(size 1.016 1.016)
					(thickness 0.1524)
				)
			)
		)
		(property "Device Type" "DFN22G6050-G6133H60"
			(at -5.022088 -8.375904 0)
			(unlocked yes)
			(layer "F.Fab")
			(hide yes)
			(effects
				(font
					(size 1.016 1.016)
					(thickness 0.1524)
				)
			)
		)
		(duplicate_pad_numbers_are_jumpers no)
		(fp_line
			(start -3.5052 -3.5179)
			(end -3.5052 -2.2479)
			(stroke
				(width 0.1524)
				(type default)
			)
			(layer "F.SilkS")
		)
		(fp_line
			(start -3.5052 2.2479)
			(end -3.5052 3.5179)
			(stroke
				(width 0.1524)
				(type default)
			)
			(layer "F.SilkS")
		)
		(fp_line
			(start -3.5052 3.5179)
			(end -2.2352 3.5179)
			(stroke
				(width 0.1524)
				(type default)
			)
			(layer "F.SilkS")
		)
		(fp_line
			(start -2.2352 -3.5179)
			(end -3.5052 -3.5179)
			(stroke
				(width 0.1524)
				(type default)
			)
			(layer "F.SilkS")
		)
		(fp_line
			(start -1.999996 -3.262122)
			(end -1.999996 -4.024122)
			(stroke
				(width 0.1524)
				(type default)
			)
			(layer "F.SilkS")
		)
		(fp_line
			(start -0.999998 3.262122)
			(end -0.999998 3.770122)
			(stroke
				(width 0.1524)
				(type default)
			)
			(layer "F.SilkS")
		)
		(fp_line
			(start 0.500126 -3.262122)
			(end 0.500126 -3.770122)
			(stroke
				(width 0.1524)
				(type default)
			)
			(layer "F.SilkS")
		)
		(fp_line
			(start 1.500124 3.262122)
			(end 1.500124 4.024122)
			(stroke
				(width 0.1524)
				(type default)
			)
			(layer "F.SilkS")
		)
		(fp_line
			(start 2.2352 3.5179)
			(end 3.5052 3.5179)
			(stroke
				(width 0.1524)
				(type default)
			)
			(layer "F.SilkS")
		)
		(fp_line
			(start 3.5052 3.5179)
			(end 3.5052 2.2479)
			(stroke
				(width 0.1524)
				(type default)
			)
			(layer "F.SilkS")
		)
		(fp_poly
			(pts
				(xy 3.5052 -3.5179) (xy 2.4765 -3.5179) (xy 3.5052 -2.4892)
			)
			(stroke
				(width 0)
				(type default)
			)
			(fill yes)
			(layer "F.SilkS")
		)
		(fp_rect
			(start -2.9972 2.5019)
			(end 2.9972 -2.5019)
			(stroke
				(width 0)
				(type default)
			)
			(fill no)
			(layer "F.CrtYd")
		)
		(fp_poly
			(pts
				(xy 3.556 -2.5019) (xy -2.9972 -2.5019) (xy -2.9972 2.5019) (xy 2.9972 2.5019) (xy 2.9972 -2.4892)
				(xy 3.556 -2.4892) (xy 3.556 3.5179) (xy -3.556 3.5179) (xy -3.556 -3.5179) (xy 3.556 -3.5179)
			)
			(stroke
				(width 0)
				(type default)
			)
			(fill no)
			(layer "F.CrtYd")
		)
		(fp_rect
			(start -3.556 3.5179)
			(end 3.556 -3.5179)
			(stroke
				(width 0)
				(type default)
			)
			(fill no)
			(layer "F.Fab")
		)
		(pad "1" smd rect
			(at 2.500122 -2.449322)
			(size 0.3048 1.1176)
			(layers "F.Cu" "F.Mask" "F.Paste")
			(net "P3V3_VFB")
		)
		(pad "2" smd rect
			(at 1.999996 -2.449322)
			(size 0.3048 1.1176)
			(layers "F.Cu" "F.Mask" "F.Paste")
			(net "P3V3_EN")
		)
		(pad "3" smd rect
			(at 1.500124 -2.449322)
			(size 0.3048 1.1176)
			(layers "F.Cu" "F.Mask" "F.Paste")
			(net "SCC_STBY_PGOOD_BUF")
		)
		(pad "4" smd rect
			(at 0.999998 -2.449322)
			(size 0.3048 1.1176)
			(layers "F.Cu" "F.Mask" "F.Paste")
			(net "P3V3_VBST")
		)
		(pad "5" smd rect
			(at 0.500126 -2.449322)
			(size 0.3048 1.1176)
			(layers "F.Cu" "F.Mask" "F.Paste")
			(net "P3V3_ROVP")
		)
		(pad "6" smd rect
			(at 0 -2.449322)
			(size 0.3048 1.1176)
			(layers "F.Cu" "F.Mask" "F.Paste")
			(net "P3V3_LL")
		)
		(pad "7" smd rect
			(at -0.500126 -2.449322)
			(size 0.3048 1.1176)
			(layers "F.Cu" "F.Mask" "F.Paste")
			(net "P3V3_LL")
		)
		(pad "8" smd rect
			(at -0.999998 -2.449322)
			(size 0.3048 1.1176)
			(layers "F.Cu" "F.Mask" "F.Paste")
			(net "P3V3_LL")
		)
		(pad "9" smd rect
			(at -1.500124 -2.449322)
			(size 0.3048 1.1176)
			(layers "F.Cu" "F.Mask" "F.Paste")
			(net "P3V3_LL")
		)
		(pad "10" smd rect
			(at -1.999996 -2.449322)
			(size 0.3048 1.1176)
			(layers "F.Cu" "F.Mask" "F.Paste")
			(net "P3V3_LL")
		)
		(pad "11" smd rect
			(at -2.500122 -2.449322)
			(size 0.3048 1.1176)
			(layers "F.Cu" "F.Mask" "F.Paste")
			(net "P3V3_LL")
		)
		(pad "12" smd rect
			(at -2.500122 2.449322)
			(size 0.3048 1.1176)
			(layers "F.Cu" "F.Mask" "F.Paste")
			(net "P12V_STBY_VIN_U10")
		)
		(pad "13" smd rect
			(at -1.999996 2.449322)
			(size 0.3048 1.1176)
			(layers "F.Cu" "F.Mask" "F.Paste")
			(net "P12V_STBY_VIN_U10")
		)
		(pad "14" smd rect
			(at -1.500124 2.449322)
			(size 0.3048 1.1176)
			(layers "F.Cu" "F.Mask" "F.Paste")
			(net "P12V_STBY_VIN_U10")
		)
		(pad "15" smd rect
			(at -0.999998 2.449322)
			(size 0.3048 1.1176)
			(layers "F.Cu" "F.Mask" "F.Paste")
			(net "P12V_STBY_VIN_U10")
		)
		(pad "16" smd rect
			(at -0.500126 2.449322)
			(size 0.3048 1.1176)
			(layers "F.Cu" "F.Mask" "F.Paste")
			(net "P12V_STBY_VIN_U10")
		)
		(pad "17" smd rect
			(at 0 2.449322)
			(size 0.3048 1.1176)
			(layers "F.Cu" "F.Mask" "F.Paste")
			(net "P12V_STBY_VIN_U10")
		)
		(pad "18" smd rect
			(at 0.500126 2.449322)
			(size 0.3048 1.1176)
			(layers "F.Cu" "F.Mask" "F.Paste")
			(net "P3V3_VREG")
		)
		(pad "19" smd rect
			(at 0.999998 2.449322)
			(size 0.3048 1.1176)
			(layers "F.Cu" "F.Mask" "F.Paste")
			(net "P12V_STBY_VDD_U10")
		)
		(pad "20" smd rect
			(at 1.500124 2.449322)
			(size 0.3048 1.1176)
			(layers "F.Cu" "F.Mask" "F.Paste")
			(net "P3V3_MODE")
		)
		(pad "21" smd rect
			(at 1.999996 2.449322)
			(size 0.3048 1.1176)
			(layers "F.Cu" "F.Mask" "F.Paste")
			(net "P3V3_TRIP")
		)
		(pad "22" smd rect
			(at 2.500122 2.449322)
			(size 0.3048 1.1176)
			(layers "F.Cu" "F.Mask" "F.Paste")
			(net "P3V3_RF")
		)
		(pad "23" smd custom
			(at 0 0)
			(size 0.83185 0.83185)
			(layers "F.Cu" "F.Mask" "F.Paste")
			(net "GND")
			(options
				(clearance outline)
				(anchor circle)
			)
			(primitives
				(gr_poly
					(pts
						(xy -2.7813 1.6637) (xy -2.7813 1.2954) (xy -3.048 1.2954) (xy -3.048 0.9525) (xy -2.7813 0.9525)
						(xy -2.7813 -0.9525) (xy -3.048 -0.9525) (xy -3.048 -1.2954) (xy -2.7813 -1.2954) (xy -2.7813 -1.6637)
						(xy 2.7813 -1.6637) (xy 2.7813 -1.2954) (xy 3.048 -1.2954) (xy 3.048 -0.9525) (xy 2.7813 -0.9525)
						(xy 2.7813 0.9525) (xy 3.048 0.9525) (xy 3.048 1.2954) (xy 2.7813 1.2954) (xy 2.7813 1.6637)
					)
					(width 0)
					(fill yes)
				)
			)
		)
	)
	(footprint ""
		(layer "F.Cu")
		(at 7.366 -78.613 90)
		(property "Reference" "R336"
			(at 0 0 90)
			(layer "F.SilkS")
			(hide yes)
			(effects
				(font
					(size 1.27 1.27)
				)
			)
		)
		(property "Value" "4K7R2F-GP"
			(at 0.064008 -3.993896 90)
			(unlocked yes)
			(layer "F.Fab")
			(hide yes)
			(effects
				(font
					(size 1.016 1.016)
					(thickness 0.1524)
				)
			)
		)
		(property "Device Type" "R402H16"
			(at 0.064008 -5.517896 90)
			(unlocked yes)
			(layer "F.Fab")
			(hide yes)
			(effects
				(font
					(size 1.016 1.016)
					(thickness 0.1524)
				)
			)
		)
		(duplicate_pad_numbers_are_jumpers no)
		(fp_line
			(start 0.508 -0.9398)
			(end -0.508 -0.9398)
			(stroke
				(width 0.1524)
				(type default)
			)
			(layer "F.SilkS")
		)
		(fp_line
			(start -0.508 -0.9398)
			(end -0.508 0.9398)
			(stroke
				(width 0.1524)
				(type default)
			)
			(layer "F.SilkS")
		)
		(fp_rect
			(start -0.508 0.9398)
			(end 0.508 -0.9398)
			(stroke
				(width 0)
				(type default)
			)
			(fill no)
			(layer "F.CrtYd")
		)
		(fp_rect
			(start -0.508 0.9398)
			(end 0.508 -0.9398)
			(stroke
				(width 0)
				(type default)
			)
			(fill no)
			(layer "F.Fab")
		)
		(pad "1" smd custom
			(at 0 -0.4445 90)
			(size 0.1397 0.1397)
			(layers "F.Cu" "F.Mask" "F.Paste")
			(net "P3V3")
			(options
				(clearance outline)
				(anchor circle)
			)
			(primitives
				(gr_poly
					(pts
						(arc
							(start -0.1778 -0.2794)
							(mid -0.249642 -0.249642)
							(end -0.2794 -0.1778)
						)
						(arc
							(start -0.2794 0.1778)
							(mid -0.249642 0.249642)
							(end -0.1778 0.2794)
						)
						(arc
							(start 0.1778 0.2794)
							(mid 0.249642 0.249642)
							(end 0.2794 0.1778)
						)
						(arc
							(start 0.2794 -0.1778)
							(mid 0.249642 -0.249642)
							(end 0.1778 -0.2794)
						)
					)
					(width 0)
					(fill yes)
				)
			)
		)
		(pad "2" smd custom
			(at 0 0.4445 90)
			(size 0.1397 0.1397)
			(layers "F.Cu" "F.Mask" "F.Paste")
			(net "EXP_EEPROM_A1")
			(options
				(clearance outline)
				(anchor circle)
			)
			(primitives
				(gr_poly
					(pts
						(arc
							(start -0.1778 -0.2794)
							(mid -0.249642 -0.249642)
							(end -0.2794 -0.1778)
						)
						(arc
							(start -0.2794 0.1778)
							(mid -0.249642 0.249642)
							(end -0.1778 0.2794)
						)
						(arc
							(start 0.1778 0.2794)
							(mid 0.249642 0.249642)
							(end 0.2794 0.1778)
						)
						(arc
							(start 0.2794 -0.1778)
							(mid 0.249642 -0.249642)
							(end 0.1778 -0.2794)
						)
					)
					(width 0)
					(fill yes)
				)
			)
		)
	)
)
